(kicad_pcb
	(version 20241229)
	(generator "pcbnew")
	(generator_version "9.0")
	(general
		(thickness 1.711)
		(legacy_teardrops no)
	)
	(paper "A4")
	(title_block
		(title "Antmicro Baseboard for Jetson AGX Thor")
		(date "2026-02-18")
		(rev "1.1.0")
		(company "Antmicro Ltd")
		(comment 1 "www.antmicro.com")
		(comment 9 "footprints 1169-1170 of 1170")
	)
	(layers
		(0 "F.Cu" signal)
		(4 "In1.Cu" signal)
		(6 "In2.Cu" signal)
		(8 "In3.Cu" signal)
		(10 "In4.Cu" jumper)
		(12 "In5.Cu" signal)
		(14 "In6.Cu" signal)
		(16 "In7.Cu" signal)
		(18 "In8.Cu" signal)
		(2 "B.Cu" signal)
		(9 "F.Adhes" user "F.Adhesive")
		(11 "B.Adhes" user "B.Adhesive")
		(13 "F.Paste" user)
		(15 "B.Paste" user)
		(5 "F.SilkS" user "F.Silkscreen")
		(7 "B.SilkS" user "B.Silkscreen")
		(1 "F.Mask" user)
		(3 "B.Mask" user)
		(17 "Dwgs.User" user "User.Drawings")
		(19 "Cmts.User" user "User.Comments")
		(21 "Eco1.User" user "User.Eco1")
		(23 "Eco2.User" user "User.Eco2")
		(25 "Edge.Cuts" user)
		(27 "Margin" user)
		(31 "F.CrtYd" user "F.Courtyard")
		(29 "B.CrtYd" user "B.Courtyard")
		(35 "F.Fab" user)
		(33 "B.Fab" user)
	)
	(footprint "antmicro-footprints:Spacer_Drill3.7mm_H8mm_9774080151R"
		(locked yes)
		(layer "B.Cu")
		(at 80.430532 63.71 -90)
		(descr "Spacer M=3 h=8mm fi=5.1mm")
		(property "Reference" "H2"
			(at 0 3.2 90)
			(layer "B.SilkS")
			(effects
				(font
					(size 0.7 0.7)
					(thickness 0.15)
				)
				(justify left bottom mirror)
			)
		)
		(property "Value" "Spacer_Drill3.7mm_H8mm_9774080151R"
			(at 0 -4 90)
			(layer "B.Fab")
			(effects
				(font
					(size 0.7 0.7)
					(thickness 0.15)
				)
				(justify left bottom mirror)
			)
		)
		(property "Datasheet" "https://www.we-online.com/components/products/datasheet/9774080151R.pdf"
			(at 0 0 90)
			(layer "B.Fab")
			(hide yes)
			(effects
				(font
					(size 1.27 1.27)
					(thickness 0.15)
				)
				(justify mirror)
			)
		)
		(property "Description" "Spacer, SMT, Non Stop, Steel, Swage Round, 5.1 mm x 8 mm, M2.5 Thread, WA-SMSI Series"
			(at 0 0 90)
			(layer "B.Fab")
			(hide yes)
			(effects
				(font
					(size 1.27 1.27)
					(thickness 0.15)
				)
				(justify mirror)
			)
		)
		(property "Manufacturer" "Würth Elektronik"
			(at 0 0 270)
			(unlocked yes)
			(layer "B.Fab")
			(hide yes)
			(effects
				(font
					(size 1 1)
					(thickness 0.15)
				)
				(justify mirror)
			)
		)
		(property "MPN" "9774080151R"
			(at 0 0 270)
			(unlocked yes)
			(layer "B.Fab")
			(hide yes)
			(effects
				(font
					(size 1 1)
					(thickness 0.15)
				)
				(justify mirror)
			)
		)
		(property "Author" "Antmicro"
			(at 0 0 270)
			(unlocked yes)
			(layer "B.Fab")
			(hide yes)
			(effects
				(font
					(size 1 1)
					(thickness 0.15)
				)
				(justify mirror)
			)
		)
		(property "License" "Apache-2.0"
			(at 0 0 270)
			(unlocked yes)
			(layer "B.Fab")
			(hide yes)
			(effects
				(font
					(size 1 1)
					(thickness 0.15)
				)
				(justify mirror)
			)
		)
		(sheetname "/")
		(sheetfile "jetson-agx-thor-baseboard.kicad_sch")
		(solder_paste_margin_ratio -1)
		(attr smd)
		(fp_circle
			(center 0 0)
			(end 3.05 0)
			(stroke
				(width 0.05)
				(type solid)
			)
			(fill no)
			(layer "B.CrtYd")
		)
		(fp_circle
			(center 0 0)
			(end 2.6 0)
			(stroke
				(width 0.15)
				(type solid)
			)
			(fill no)
			(layer "B.Fab")
		)
		(fp_text user "License: Apache-2.0"
			(at -9.6 -8.9 90)
			(layer "B.Fab")
			(effects
				(font
					(size 0.7 0.7)
					(thickness 0.15)
				)
				(justify left bottom mirror)
			)
		)
		(fp_text user "${REFERENCE}"
			(at -9.6 -6.5 90)
			(layer "B.Fab")
			(effects
				(font
					(size 0.7 0.7)
					(thickness 0.15)
				)
				(justify left bottom mirror)
			)
		)
		(fp_text user "Author: Antmicro"
			(at -9.6 -7.7 90)
			(layer "B.Fab")
			(effects
				(font
					(size 0.7 0.7)
					(thickness 0.15)
				)
				(justify left bottom mirror)
			)
		)
		(pad "" smd custom
			(at -1.7 -1.7 180)
			(size 0.62 0.62)
			(layers "B.Paste")
			(thermal_bridge_angle 90)
			(options
				(clearance outline)
				(anchor circle)
			)
			(primitives
				(gr_arc
					(start 1.266786 0.24747)
					(mid 0.285453 -0.29439)
					(end -0.250195 -1.279127)
					(width 0.2)
				)
				(gr_arc
					(start 1.259603 0.339191)
					(mid 0.218448 -0.232561)
					(end -0.34334 -1.279127)
					(width 0.2)
				)
				(gr_arc
					(start 1.255279 0.431435)
					(mid 0.152481 -0.169693)
					(end -0.436309 -1.279127)
					(width 0.2)
				)
				(gr_arc
					(start 1.253811 0.524161)
					(mid 0.087542 -0.105784)
					(end -0.529126 -1.279127)
					(width 0.2)
				)
				(gr_arc
					(start 1.275473 0.621136)
					(mid 0.0309 -0.033527)
					(end -0.621807 -1.279127)
					(width 0.2)
				)
				(gr_arc
					(start 1.263664 0.711602)
					(mid -0.037759 0.026651)
					(end -0.71437 -1.279127)
					(width 0.2)
				)
				(gr_arc
					(start 1.253435 0.802342)
					(mid -0.105837 0.087395)
					(end -0.806826 -1.279127)
					(width 0.2)
				)
				(gr_arc
					(start 1.267475 0.897258)
					(mid -0.165236 0.156885)
					(end -0.899187 -1.279127)
					(width 0.2)
				)
				(gr_arc
					(start 1.270645 0.990112)
					(mid -0.228522 0.222449)
					(end -0.991463 -1.279127)
					(width 0.2)
				)
				(gr_arc
					(start 1.266278 1.081674)
					(mid -0.294507 0.285313)
					(end -1.083663 -1.279127)
					(width 0.2)
				)
				(gr_line
					(start 1.279127 0.250195)
					(end 1.279127 1.083663)
					(width 0.2)
				)
				(gr_line
					(start -0.250195 -1.279127)
					(end -1.083663 -1.279127)
					(width 0.2)
				)
			)
		)
		(pad "" smd custom
			(at -1.7 1.7 270)
			(size 0.62 0.62)
			(layers "B.Paste")
			(thermal_bridge_angle 90)
			(options
				(clearance outline)
				(anchor circle)
			)
			(primitives
				(gr_arc
					(start 1.266786 0.24747)
					(mid 0.285453 -0.29439)
					(end -0.250195 -1.279127)
					(width 0.2)
				)
				(gr_arc
					(start 1.259603 0.339191)
					(mid 0.218448 -0.232561)
					(end -0.34334 -1.279127)
					(width 0.2)
				)
				(gr_arc
					(start 1.255279 0.431435)
					(mid 0.152481 -0.169693)
					(end -0.436309 -1.279127)
					(width 0.2)
				)
				(gr_arc
					(start 1.253811 0.524161)
					(mid 0.087542 -0.105784)
					(end -0.529126 -1.279127)
					(width 0.2)
				)
				(gr_arc
					(start 1.275473 0.621136)
					(mid 0.0309 -0.033527)
					(end -0.621807 -1.279127)
					(width 0.2)
				)
				(gr_arc
					(start 1.263664 0.711602)
					(mid -0.037759 0.026651)
					(end -0.71437 -1.279127)
					(width 0.2)
				)
				(gr_arc
					(start 1.253435 0.802342)
					(mid -0.105837 0.087395)
					(end -0.806826 -1.279127)
					(width 0.2)
				)
				(gr_arc
					(start 1.267475 0.897258)
					(mid -0.165236 0.156885)
					(end -0.899187 -1.279127)
					(width 0.2)
				)
				(gr_arc
					(start 1.270645 0.990112)
					(mid -0.228522 0.222449)
					(end -0.991463 -1.279127)
					(width 0.2)
				)
				(gr_arc
					(start 1.266278 1.081674)
					(mid -0.294507 0.285313)
					(end -1.083663 -1.279127)
					(width 0.2)
				)
				(gr_line
					(start 1.279127 0.250195)
					(end 1.279127 1.083663)
					(width 0.2)
				)
				(gr_line
					(start -0.250195 -1.279127)
					(end -1.083663 -1.279127)
					(width 0.2)
				)
			)
		)
		(pad "" smd custom
			(at 1.7 -1.7 90)
			(size 0.62 0.62)
			(layers "B.Paste")
			(thermal_bridge_angle 90)
			(options
				(clearance outline)
				(anchor circle)
			)
			(primitives
				(gr_arc
					(start 1.266786 0.24747)
					(mid 0.285453 -0.29439)
					(end -0.250195 -1.279127)
					(width 0.2)
				)
				(gr_arc
					(start 1.259603 0.339191)
					(mid 0.218448 -0.232561)
					(end -0.34334 -1.279127)
					(width 0.2)
				)
				(gr_arc
					(start 1.255279 0.431435)
					(mid 0.152481 -0.169693)
					(end -0.436309 -1.279127)
					(width 0.2)
				)
				(gr_arc
					(start 1.253811 0.524161)
					(mid 0.087542 -0.105784)
					(end -0.529126 -1.279127)
					(width 0.2)
				)
				(gr_arc
					(start 1.275473 0.621136)
					(mid 0.0309 -0.033527)
					(end -0.621807 -1.279127)
					(width 0.2)
				)
				(gr_arc
					(start 1.263664 0.711602)
					(mid -0.037759 0.026651)
					(end -0.71437 -1.279127)
					(width 0.2)
				)
				(gr_arc
					(start 1.253435 0.802342)
					(mid -0.105837 0.087395)
					(end -0.806826 -1.279127)
					(width 0.2)
				)
				(gr_arc
					(start 1.267475 0.897258)
					(mid -0.165236 0.156885)
					(end -0.899187 -1.279127)
					(width 0.2)
				)
				(gr_arc
					(start 1.270645 0.990112)
					(mid -0.228522 0.222449)
					(end -0.991463 -1.279127)
					(width 0.2)
				)
				(gr_arc
					(start 1.266278 1.081674)
					(mid -0.294507 0.285313)
					(end -1.083663 -1.279127)
					(width 0.2)
				)
				(gr_line
					(start 1.279127 0.250195)
					(end 1.279127 1.083663)
					(width 0.2)
				)
				(gr_line
					(start -0.250195 -1.279127)
					(end -1.083663 -1.279127)
					(width 0.2)
				)
			)
		)
		(pad "" smd custom
			(at 1.7 1.7)
			(size 0.62 0.62)
			(layers "B.Paste")
			(thermal_bridge_angle 90)
			(options
				(clearance outline)
				(anchor circle)
			)
			(primitives
				(gr_arc
					(start 1.266786 0.24747)
					(mid 0.285453 -0.29439)
					(end -0.250195 -1.279127)
					(width 0.2)
				)
				(gr_arc
					(start 1.259603 0.339191)
					(mid 0.218448 -0.232561)
					(end -0.34334 -1.279127)
					(width 0.2)
				)
				(gr_arc
					(start 1.255279 0.431435)
					(mid 0.152481 -0.169693)
					(end -0.436309 -1.279127)
					(width 0.2)
				)
				(gr_arc
					(start 1.253811 0.524161)
					(mid 0.087542 -0.105784)
					(end -0.529126 -1.279127)
					(width 0.2)
				)
				(gr_arc
					(start 1.275473 0.621136)
					(mid 0.0309 -0.033527)
					(end -0.621807 -1.279127)
					(width 0.2)
				)
				(gr_arc
					(start 1.263664 0.711602)
					(mid -0.037759 0.026651)
					(end -0.71437 -1.279127)
					(width 0.2)
				)
				(gr_arc
					(start 1.253435 0.802342)
					(mid -0.105837 0.087395)
					(end -0.806826 -1.279127)
					(width 0.2)
				)
				(gr_arc
					(start 1.267475 0.897258)
					(mid -0.165236 0.156885)
					(end -0.899187 -1.279127)
					(width 0.2)
				)
				(gr_arc
					(start 1.270645 0.990112)
					(mid -0.228522 0.222449)
					(end -0.991463 -1.279127)
					(width 0.2)
				)
				(gr_arc
					(start 1.266278 1.081674)
					(mid -0.294507 0.285313)
					(end -1.083663 -1.279127)
					(width 0.2)
				)
				(gr_line
					(start 1.279127 0.250195)
					(end 1.279127 1.083663)
					(width 0.2)
				)
				(gr_line
					(start -0.250195 -1.279127)
					(end -1.083663 -1.279127)
					(width 0.2)
				)
			)
		)
		(pad "1" thru_hole circle
			(at 0 0 270)
			(size 6 6)
			(drill 3.7)
			(layers "*.Cu" "*.Mask")
			(remove_unused_layers no)
			(net 1 "GND")
			(pintype "passive")
		)
	)
	(footprint "antmicro-footprints:C_0805_2012Metric"
		(layer "B.Cu")
		(at 229.4 133.8 90)
		(descr "Capacitor SMD 0805")
		(tags "capacitor SMD 0805")
		(property "Reference" "C105"
			(at -1.4 -1.9 90)
			(layer "B.SilkS")
			(effects
				(font
					(size 0.7 0.7)
					(thickness 0.15)
				)
				(justify right top mirror)
			)
		)
		(property "Value" "C_22u_25V_0805"
			(at -2.055717 -1.963153 90)
			(layer "B.Fab")
			(effects
				(font
					(size 0.7 0.7)
					(thickness 0.15)
				)
				(justify right top mirror)
			)
		)
		(property "Datasheet" "https://product.samsungsem.com/mlcc/CL21A226MAYNNN.do"
			(at 0 0 90)
			(layer "B.Fab")
			(hide yes)
			(effects
				(font
					(size 1.27 1.27)
					(thickness 0.15)
				)
				(justify mirror)
			)
		)
		(property "Description" "SMT Multilayer Ceramic Capacitor, 22uF, +/-20%, 25V, X5R, 0805 [2012 Metric]"
			(at 0 0 90)
			(layer "B.Fab")
			(hide yes)
			(effects
				(font
					(size 1.27 1.27)
					(thickness 0.15)
				)
				(justify mirror)
			)
		)
		(property "Manufacturer" "Samsung Electro-Mechanics"
			(at 0 0 90)
			(unlocked yes)
			(layer "B.Fab")
			(hide yes)
			(effects
				(font
					(size 1 1)
					(thickness 0.15)
				)
				(justify mirror)
			)
		)
		(property "MPN" "CL21A226MAYNNNE"
			(at 0 0 90)
			(unlocked yes)
			(layer "B.Fab")
			(hide yes)
			(effects
				(font
					(size 1 1)
					(thickness 0.15)
				)
				(justify mirror)
			)
		)
		(property "Val" "22u"
			(at 0 0 90)
			(unlocked yes)
			(layer "B.Fab")
			(hide yes)
			(effects
				(font
					(size 1 1)
					(thickness 0.15)
				)
				(justify mirror)
			)
		)
		(property "License" "Apache-2.0"
			(at 0 0 90)
			(unlocked yes)
			(layer "B.Fab")
			(hide yes)
			(effects
				(font
					(size 1 1)
					(thickness 0.15)
				)
				(justify mirror)
			)
		)
		(property "Author" "Antmicro"
			(at 0 0 90)
			(unlocked yes)
			(layer "B.Fab")
			(hide yes)
			(effects
				(font
					(size 1 1)
					(thickness 0.15)
				)
				(justify mirror)
			)
		)
		(property "Voltage" "25V"
			(at 0 0 90)
			(unlocked yes)
			(layer "B.Fab")
			(hide yes)
			(effects
				(font
					(size 1 1)
					(thickness 0.15)
				)
				(justify mirror)
			)
		)
		(property "Dielectric" "X5R"
			(at 0 0 90)
			(unlocked yes)
			(layer "B.Fab")
			(hide yes)
			(effects
				(font
					(size 1 1)
					(thickness 0.15)
				)
				(justify mirror)
			)
		)
		(property "Public" "False"
			(at 0 0 90)
			(unlocked yes)
			(layer "B.Fab")
			(hide yes)
			(effects
				(font
					(size 1 1)
					(thickness 0.15)
				)
				(justify mirror)
			)
		)
		(sheetname "/USB Hub/")
		(sheetfile "usb_hub.kicad_sch")
		(attr smd)
		(fp_line
			(start -0.3 -0.7)
			(end 0.3 -0.7)
			(stroke
				(width 0.15)
				(type solid)
			)
			(layer "B.SilkS")
		)
		(fp_line
			(start -0.3 0.7)
			(end 0.3 0.7)
			(stroke
				(width 0.15)
				(type solid)
			)
			(layer "B.SilkS")
		)
		(fp_poly
			(pts
				(xy 1.95 0.9) (xy -1.95 0.9) (xy -1.95 -0.9) (xy 1.95 -0.9)
			)
			(stroke
				(width 0.05)
				(type default)
			)
			(fill no)
			(layer "B.CrtYd")
		)
		(fp_poly
			(pts
				(xy -0.95 0.675001) (xy 0.95 0.675001) (xy 0.95 -0.675001) (xy -0.95 -0.675001)
			)
			(stroke
				(width 0.15)
				(type solid)
			)
			(fill no)
			(layer "B.Fab")
		)
		(fp_text user "License: Apache-2.0"
			(at -1.9 -4.947 90)
			(layer "B.Fab")
			(effects
				(font
					(size 0.7 0.7)
					(thickness 0.15)
				)
				(justify right top mirror)
			)
		)
		(fp_text user "${REFERENCE}"
			(at -1.899999 -3.947 90)
			(layer "B.Fab")
			(effects
				(font
					(size 0.7 0.7)
					(thickness 0.15)
				)
				(justify right top mirror)
			)
		)
		(fp_text user "Author: Antmicro"
			(at -1.9 -5.947 90)
			(layer "B.Fab")
			(effects
				(font
					(size 0.7 0.7)
					(thickness 0.15)
				)
				(justify right top mirror)
			)
		)
		(pad "1" smd roundrect
			(at -1.099999 0 90)
			(size 1.2 1.3)
			(layers "B.Cu" "B.Mask" "B.Paste")
			(roundrect_rratio 0.25)
			(net 115 "/USB Hub/USBC4_VBUS")
			(pintype "passive")
		)
		(pad "2" smd roundrect
			(at 1.099999 0 90)
			(size 1.2 1.3)
			(layers "B.Cu" "B.Mask" "B.Paste")
			(roundrect_rratio 0.25)
			(net 1 "GND")
			(pintype "passive")
		)
	)
)
